(kicad_pcb
	(version 20260206)
	(generator "pcbnew")
	(generator_version "10.0")
	(general
		(thickness 1.6)
		(legacy_teardrops no)
	)
	(paper "A4")
	(title_block
		(title "01162023_DA0F0TEBIF0_F0T_Expander_BD_F_brd_V02_OCP.brd")
		(comment 1 "Grand Teton / footprints 3813-3818 of 9728")
	)
	(layers
		(0 "F.Cu" signal "TOP")
		(4 "In1.Cu" signal "GND")
		(6 "In2.Cu" signal "VCC")
		(8 "In3.Cu" signal "VCC1")
		(10 "In4.Cu" signal "GND1")
		(12 "In5.Cu" signal "IN1")
		(14 "In6.Cu" signal "GND2")
		(16 "In7.Cu" signal "IN2")
		(18 "In8.Cu" signal "GND3")
		(20 "In9.Cu" signal "IN3")
		(22 "In10.Cu" signal "GND4")
		(24 "In11.Cu" signal "IN4")
		(26 "In12.Cu" signal "GND5")
		(28 "In13.Cu" signal "IN5")
		(30 "In14.Cu" signal "GND6")
		(32 "In15.Cu" signal "IN6")
		(34 "In16.Cu" signal "GND7")
		(2 "B.Cu" signal "BOTTOM")
		(9 "F.Adhes" user "F.Adhesive")
		(11 "B.Adhes" user "B.Adhesive")
		(13 "F.Paste" user "Package Geometry/Pastemask Top")
		(15 "B.Paste" user "Package Geometry/Pastemask Bottom")
		(5 "F.SilkS" user "Ref Des/Silkscreen Top")
		(7 "B.SilkS" user "Ref Des/Silkscreen Bottom")
		(1 "F.Mask" user "Board Geometry/Soldermask Top")
		(3 "B.Mask" user "Board Geometry/Soldermask Bottom")
		(17 "Dwgs.User" user "User.Drawings")
		(19 "Cmts.User" user "User.Comments")
		(21 "Eco1.User" user "User.Eco1")
		(23 "Eco2.User" user "User.Eco2")
		(25 "Edge.Cuts" user "Board Geometry/Outline")
		(27 "Margin" user)
		(31 "F.CrtYd" user "Package Geometry/Place Bound Top")
		(29 "B.CrtYd" user "Package Geometry/Place Bound Bottom")
		(35 "F.Fab" user "Ref Des/Assembly Top")
		(33 "B.Fab" user "Ref Des/Assembly Bottom")
	)
	(footprint ""
		(layer "F.Cu")
		(at 5.462524 -255.046734 -90)
		(property "Reference" "R6472"
			(at 0 0 270)
			(layer "F.SilkS")
			(hide yes)
			(effects
				(font
					(size 1.27 1.27)
				)
			)
		)
		(property "Value" ""
			(at 0 0 270)
			(layer "F.Fab")
			(effects
				(font
					(size 1.27 1.27)
				)
			)
		)
		(duplicate_pad_numbers_are_jumpers no)
		(fp_line
			(start -0.7874 0.4064)
			(end -0.7874 -0.4064)
			(stroke
				(width 0.1524)
				(type default)
			)
			(layer "F.SilkS")
		)
		(fp_line
			(start 0.7874 0.4064)
			(end -0.7874 0.4064)
			(stroke
				(width 0.1524)
				(type default)
			)
			(layer "F.SilkS")
		)
		(fp_line
			(start -0.7874 -0.4064)
			(end 0.7874 -0.4064)
			(stroke
				(width 0.1524)
				(type default)
			)
			(layer "F.SilkS")
		)
		(fp_line
			(start 0.7874 -0.4064)
			(end 0.7874 0.4064)
			(stroke
				(width 0.1524)
				(type default)
			)
			(layer "F.SilkS")
		)
		(fp_line
			(start -0.67945 0.3048)
			(end -0.67945 -0.305054)
			(stroke
				(width 0.1)
				(type default)
			)
			(layer "F.Fab")
		)
		(fp_line
			(start -0.12065 0.3048)
			(end -0.67945 0.3048)
			(stroke
				(width 0.1)
				(type default)
			)
			(layer "F.Fab")
		)
		(fp_line
			(start 0.120396 0.3048)
			(end 0.120396 0.2794)
			(stroke
				(width 0.1)
				(type default)
			)
			(layer "F.Fab")
		)
		(fp_line
			(start 0.67945 0.3048)
			(end 0.120396 0.3048)
			(stroke
				(width 0.1)
				(type default)
			)
			(layer "F.Fab")
		)
		(fp_line
			(start -0.12065 0.2794)
			(end -0.12065 0.3048)
			(stroke
				(width 0.1)
				(type default)
			)
			(layer "F.Fab")
		)
		(fp_line
			(start 0.120396 0.2794)
			(end -0.12065 0.2794)
			(stroke
				(width 0.1)
				(type default)
			)
			(layer "F.Fab")
		)
		(fp_line
			(start -0.12065 -0.2794)
			(end 0.12065 -0.2794)
			(stroke
				(width 0.1)
				(type default)
			)
			(layer "F.Fab")
		)
		(fp_line
			(start 0.12065 -0.2794)
			(end 0.12065 -0.3048)
			(stroke
				(width 0.1)
				(type default)
			)
			(layer "F.Fab")
		)
		(fp_line
			(start 0.12065 -0.3048)
			(end 0.67945 -0.3048)
			(stroke
				(width 0.1)
				(type default)
			)
			(layer "F.Fab")
		)
		(fp_line
			(start 0.67945 -0.3048)
			(end 0.67945 0.3048)
			(stroke
				(width 0.1)
				(type default)
			)
			(layer "F.Fab")
		)
		(fp_line
			(start -0.67945 -0.305054)
			(end -0.12065 -0.305054)
			(stroke
				(width 0.1)
				(type default)
			)
			(layer "F.Fab")
		)
		(fp_line
			(start -0.12065 -0.305054)
			(end -0.12065 -0.2794)
			(stroke
				(width 0.1)
				(type default)
			)
			(layer "F.Fab")
		)
		(pad "1" smd circle
			(at -0.40005 0 270)
			(size 0 0)
			(layers "F.Cu" "F.Mask" "F.Paste")
			(net "P1V25_SERDES_VDDPLL_PEX0")
		)
		(pad "2" smd circle
			(at 0.40005 0 270)
			(size 0 0)
			(layers "F.Cu" "F.Mask" "F.Paste")
			(net "P1V25_SERDES_VDDPLL_PEX0_C9")
		)
	)
	(footprint ""
		(layer "F.Cu")
		(at 405.015192 -59.546236 90)
		(property "Reference" "C2898"
			(at 0 0 90)
			(layer "F.SilkS")
			(hide yes)
			(effects
				(font
					(size 1.27 1.27)
				)
			)
		)
		(property "Value" ""
			(at 0 0 90)
			(layer "F.Fab")
			(effects
				(font
					(size 1.27 1.27)
				)
			)
		)
		(duplicate_pad_numbers_are_jumpers no)
		(fp_line
			(start 0.7874 -0.4064)
			(end 0.7874 0.4064)
			(stroke
				(width 0.1524)
				(type default)
			)
			(layer "F.SilkS")
		)
		(fp_line
			(start -0.7874 -0.4064)
			(end 0.7874 -0.4064)
			(stroke
				(width 0.1524)
				(type default)
			)
			(layer "F.SilkS")
		)
		(fp_line
			(start 0.7874 0.4064)
			(end -0.7874 0.4064)
			(stroke
				(width 0.1524)
				(type default)
			)
			(layer "F.SilkS")
		)
		(fp_line
			(start -0.7874 0.4064)
			(end -0.7874 -0.4064)
			(stroke
				(width 0.1524)
				(type default)
			)
			(layer "F.SilkS")
		)
		(fp_line
			(start -0.12065 -0.305054)
			(end -0.12065 -0.2794)
			(stroke
				(width 0.1)
				(type default)
			)
			(layer "F.Fab")
		)
		(fp_line
			(start -0.67945 -0.305054)
			(end -0.12065 -0.305054)
			(stroke
				(width 0.1)
				(type default)
			)
			(layer "F.Fab")
		)
		(fp_line
			(start 0.67945 -0.3048)
			(end 0.67945 0.3048)
			(stroke
				(width 0.1)
				(type default)
			)
			(layer "F.Fab")
		)
		(fp_line
			(start 0.12065 -0.3048)
			(end 0.67945 -0.3048)
			(stroke
				(width 0.1)
				(type default)
			)
			(layer "F.Fab")
		)
		(fp_line
			(start 0.12065 -0.2794)
			(end 0.12065 -0.3048)
			(stroke
				(width 0.1)
				(type default)
			)
			(layer "F.Fab")
		)
		(fp_line
			(start -0.12065 -0.2794)
			(end 0.12065 -0.2794)
			(stroke
				(width 0.1)
				(type default)
			)
			(layer "F.Fab")
		)
		(fp_line
			(start 0.120396 0.2794)
			(end -0.12065 0.2794)
			(stroke
				(width 0.1)
				(type default)
			)
			(layer "F.Fab")
		)
		(fp_line
			(start -0.12065 0.2794)
			(end -0.12065 0.3048)
			(stroke
				(width 0.1)
				(type default)
			)
			(layer "F.Fab")
		)
		(fp_line
			(start 0.67945 0.3048)
			(end 0.120396 0.3048)
			(stroke
				(width 0.1)
				(type default)
			)
			(layer "F.Fab")
		)
		(fp_line
			(start 0.120396 0.3048)
			(end 0.120396 0.2794)
			(stroke
				(width 0.1)
				(type default)
			)
			(layer "F.Fab")
		)
		(fp_line
			(start -0.12065 0.3048)
			(end -0.67945 0.3048)
			(stroke
				(width 0.1)
				(type default)
			)
			(layer "F.Fab")
		)
		(fp_line
			(start -0.67945 0.3048)
			(end -0.67945 -0.305054)
			(stroke
				(width 0.1)
				(type default)
			)
			(layer "F.Fab")
		)
		(pad "1" smd circle
			(at -0.40005 0 90)
			(size 0 0)
			(layers "F.Cu" "F.Mask" "F.Paste")
			(net "SSD14_AUX_P3V3_EN_R")
		)
		(pad "2" smd circle
			(at 0.40005 0 90)
			(size 0 0)
			(layers "F.Cu" "F.Mask" "F.Paste")
			(net "GND")
		)
	)
	(footprint ""
		(layer "F.Cu")
		(at 233.871008 -83.318858 90)
		(property "Reference" "R1011"
			(at 0 0 90)
			(layer "F.SilkS")
			(hide yes)
			(effects
				(font
					(size 1.27 1.27)
				)
			)
		)
		(property "Value" ""
			(at 0 0 90)
			(layer "F.Fab")
			(effects
				(font
					(size 1.27 1.27)
				)
			)
		)
		(duplicate_pad_numbers_are_jumpers no)
		(fp_line
			(start -0.015748 -0.4064)
			(end 0.7874 -0.4064)
			(stroke
				(width 0.1524)
				(type default)
			)
			(layer "F.SilkS")
		)
		(fp_line
			(start 0.7874 0.4064)
			(end -0.7874 0.4064)
			(stroke
				(width 0.1524)
				(type default)
			)
			(layer "F.SilkS")
		)
		(fp_line
			(start -0.7874 0.4064)
			(end -0.7874 -0.4064)
			(stroke
				(width 0.1524)
				(type default)
			)
			(layer "F.SilkS")
		)
		(fp_line
			(start -0.12065 -0.305054)
			(end -0.12065 -0.2794)
			(stroke
				(width 0.1)
				(type default)
			)
			(layer "F.Fab")
		)
		(fp_line
			(start -0.67945 -0.305054)
			(end -0.12065 -0.305054)
			(stroke
				(width 0.1)
				(type default)
			)
			(layer "F.Fab")
		)
		(fp_line
			(start 0.67945 -0.3048)
			(end 0.67945 0.3048)
			(stroke
				(width 0.1)
				(type default)
			)
			(layer "F.Fab")
		)
		(fp_line
			(start 0.12065 -0.3048)
			(end 0.67945 -0.3048)
			(stroke
				(width 0.1)
				(type default)
			)
			(layer "F.Fab")
		)
		(fp_line
			(start 0.12065 -0.2794)
			(end 0.12065 -0.3048)
			(stroke
				(width 0.1)
				(type default)
			)
			(layer "F.Fab")
		)
		(fp_line
			(start -0.12065 -0.2794)
			(end 0.12065 -0.2794)
			(stroke
				(width 0.1)
				(type default)
			)
			(layer "F.Fab")
		)
		(fp_line
			(start 0.120396 0.2794)
			(end -0.12065 0.2794)
			(stroke
				(width 0.1)
				(type default)
			)
			(layer "F.Fab")
		)
		(fp_line
			(start -0.12065 0.2794)
			(end -0.12065 0.3048)
			(stroke
				(width 0.1)
				(type default)
			)
			(layer "F.Fab")
		)
		(fp_line
			(start 0.67945 0.3048)
			(end 0.120396 0.3048)
			(stroke
				(width 0.1)
				(type default)
			)
			(layer "F.Fab")
		)
		(fp_line
			(start 0.120396 0.3048)
			(end 0.120396 0.2794)
			(stroke
				(width 0.1)
				(type default)
			)
			(layer "F.Fab")
		)
		(fp_line
			(start -0.12065 0.3048)
			(end -0.67945 0.3048)
			(stroke
				(width 0.1)
				(type default)
			)
			(layer "F.Fab")
		)
		(fp_line
			(start -0.67945 0.3048)
			(end -0.67945 -0.305054)
			(stroke
				(width 0.1)
				(type default)
			)
			(layer "F.Fab")
		)
		(pad "1" smd rect
			(at -0.40005 0 270)
			(size 0.4572 0.508)
			(layers "F.Cu" "F.Mask" "F.Paste")
			(net "USB2_FT4232_SDB_R_DP")
		)
		(pad "2" smd rect
			(at 0.40005 0 270)
			(size 0.4572 0.508)
			(layers "F.Cu" "F.Mask" "F.Paste")
			(net "USB2_FT4232_SDB_DP")
		)
	)
	(footprint ""
		(layer "F.Cu")
		(at 188.775086 -56.977534 180)
		(property "Reference" "PC378"
			(at 0 0 180)
			(layer "F.SilkS")
			(hide yes)
			(effects
				(font
					(size 1.27 1.27)
				)
			)
		)
		(property "Value" ""
			(at 0 0 180)
			(layer "F.Fab")
			(effects
				(font
					(size 1.27 1.27)
				)
			)
		)
		(duplicate_pad_numbers_are_jumpers no)
		(fp_line
			(start 0.7874 0.4064)
			(end -0.7874 0.4064)
			(stroke
				(width 0.1524)
				(type default)
			)
			(layer "F.SilkS")
		)
		(fp_line
			(start 0.7874 -0.4064)
			(end 0.7874 0.4064)
			(stroke
				(width 0.1524)
				(type default)
			)
			(layer "F.SilkS")
		)
		(fp_line
			(start -0.7874 0.4064)
			(end -0.7874 -0.4064)
			(stroke
				(width 0.1524)
				(type default)
			)
			(layer "F.SilkS")
		)
		(fp_line
			(start -0.7874 -0.4064)
			(end 0.7874 -0.4064)
			(stroke
				(width 0.1524)
				(type default)
			)
			(layer "F.SilkS")
		)
		(fp_line
			(start 0.67945 0.3048)
			(end 0.120396 0.3048)
			(stroke
				(width 0.1)
				(type default)
			)
			(layer "F.Fab")
		)
		(fp_line
			(start 0.67945 -0.3048)
			(end 0.67945 0.3048)
			(stroke
				(width 0.1)
				(type default)
			)
			(layer "F.Fab")
		)
		(fp_line
			(start 0.12065 -0.2794)
			(end 0.12065 -0.3048)
			(stroke
				(width 0.1)
				(type default)
			)
			(layer "F.Fab")
		)
		(fp_line
			(start 0.12065 -0.3048)
			(end 0.67945 -0.3048)
			(stroke
				(width 0.1)
				(type default)
			)
			(layer "F.Fab")
		)
		(fp_line
			(start 0.120396 0.3048)
			(end 0.120396 0.2794)
			(stroke
				(width 0.1)
				(type default)
			)
			(layer "F.Fab")
		)
		(fp_line
			(start 0.120396 0.2794)
			(end -0.12065 0.2794)
			(stroke
				(width 0.1)
				(type default)
			)
			(layer "F.Fab")
		)
		(fp_line
			(start -0.12065 0.3048)
			(end -0.67945 0.3048)
			(stroke
				(width 0.1)
				(type default)
			)
			(layer "F.Fab")
		)
		(fp_line
			(start -0.12065 0.2794)
			(end -0.12065 0.3048)
			(stroke
				(width 0.1)
				(type default)
			)
			(layer "F.Fab")
		)
		(fp_line
			(start -0.12065 -0.2794)
			(end 0.12065 -0.2794)
			(stroke
				(width 0.1)
				(type default)
			)
			(layer "F.Fab")
		)
		(fp_line
			(start -0.12065 -0.305054)
			(end -0.12065 -0.2794)
			(stroke
				(width 0.1)
				(type default)
			)
			(layer "F.Fab")
		)
		(fp_line
			(start -0.67945 0.3048)
			(end -0.67945 -0.305054)
			(stroke
				(width 0.1)
				(type default)
			)
			(layer "F.Fab")
		)
		(fp_line
			(start -0.67945 -0.305054)
			(end -0.12065 -0.305054)
			(stroke
				(width 0.1)
				(type default)
			)
			(layer "F.Fab")
		)
		(pad "1" smd circle
			(at -0.40005 0 180)
			(size 0 0)
			(layers "F.Cu" "F.Mask" "F.Paste")
			(net "P12V_AUX")
		)
		(pad "2" smd circle
			(at 0.40005 0 180)
			(size 0 0)
			(layers "F.Cu" "F.Mask" "F.Paste")
			(net "GND")
		)
	)
	(footprint ""
		(layer "F.Cu")
		(at 326.694038 -117.426486)
		(property "Reference" "PC906"
			(at 0 0 0)
			(layer "F.SilkS")
			(hide yes)
			(effects
				(font
					(size 1.27 1.27)
				)
			)
		)
		(property "Value" ""
			(at 0 0 0)
			(layer "F.Fab")
			(effects
				(font
					(size 1.27 1.27)
				)
			)
		)
		(duplicate_pad_numbers_are_jumpers no)
		(fp_line
			(start -0.7874 -0.4064)
			(end 0.7874 -0.4064)
			(stroke
				(width 0.1524)
				(type default)
			)
			(layer "F.SilkS")
		)
		(fp_line
			(start -0.7874 0.4064)
			(end -0.7874 -0.4064)
			(stroke
				(width 0.1524)
				(type default)
			)
			(layer "F.SilkS")
		)
		(fp_line
			(start 0.7874 -0.4064)
			(end 0.7874 0.4064)
			(stroke
				(width 0.1524)
				(type default)
			)
			(layer "F.SilkS")
		)
		(fp_line
			(start 0.7874 0.4064)
			(end -0.7874 0.4064)
			(stroke
				(width 0.1524)
				(type default)
			)
			(layer "F.SilkS")
		)
		(fp_line
			(start -0.67945 -0.305054)
			(end -0.12065 -0.305054)
			(stroke
				(width 0.1)
				(type default)
			)
			(layer "F.Fab")
		)
		(fp_line
			(start -0.67945 0.3048)
			(end -0.67945 -0.305054)
			(stroke
				(width 0.1)
				(type default)
			)
			(layer "F.Fab")
		)
		(fp_line
			(start -0.12065 -0.305054)
			(end -0.12065 -0.2794)
			(stroke
				(width 0.1)
				(type default)
			)
			(layer "F.Fab")
		)
		(fp_line
			(start -0.12065 -0.2794)
			(end 0.12065 -0.2794)
			(stroke
				(width 0.1)
				(type default)
			)
			(layer "F.Fab")
		)
		(fp_line
			(start -0.12065 0.2794)
			(end -0.12065 0.3048)
			(stroke
				(width 0.1)
				(type default)
			)
			(layer "F.Fab")
		)
		(fp_line
			(start -0.12065 0.3048)
			(end -0.67945 0.3048)
			(stroke
				(width 0.1)
				(type default)
			)
			(layer "F.Fab")
		)
		(fp_line
			(start 0.120396 0.2794)
			(end -0.12065 0.2794)
			(stroke
				(width 0.1)
				(type default)
			)
			(layer "F.Fab")
		)
		(fp_line
			(start 0.120396 0.3048)
			(end 0.120396 0.2794)
			(stroke
				(width 0.1)
				(type default)
			)
			(layer "F.Fab")
		)
		(fp_line
			(start 0.12065 -0.3048)
			(end 0.67945 -0.3048)
			(stroke
				(width 0.1)
				(type default)
			)
			(layer "F.Fab")
		)
		(fp_line
			(start 0.12065 -0.2794)
			(end 0.12065 -0.3048)
			(stroke
				(width 0.1)
				(type default)
			)
			(layer "F.Fab")
		)
		(fp_line
			(start 0.67945 -0.3048)
			(end 0.67945 0.3048)
			(stroke
				(width 0.1)
				(type default)
			)
			(layer "F.Fab")
		)
		(fp_line
			(start 0.67945 0.3048)
			(end 0.120396 0.3048)
			(stroke
				(width 0.1)
				(type default)
			)
			(layer "F.Fab")
		)
		(pad "1" smd circle
			(at -0.40005 0)
			(size 0 0)
			(layers "F.Cu" "F.Mask" "F.Paste")
			(net "P3V3_NIC5_CO_MODE")
		)
		(pad "2" smd circle
			(at 0.40005 0)
			(size 0 0)
			(layers "F.Cu" "F.Mask" "F.Paste")
			(net "GND")
		)
	)
	(footprint ""
		(layer "F.Cu")
		(at 294.50919 -210.094068 -90)
		(property "Reference" "R3368"
			(at 0 0 270)
			(layer "F.SilkS")
			(hide yes)
			(effects
				(font
					(size 1.27 1.27)
				)
			)
		)
		(property "Value" ""
			(at 0 0 270)
			(layer "F.Fab")
			(effects
				(font
					(size 1.27 1.27)
				)
			)
		)
		(duplicate_pad_numbers_are_jumpers no)
		(fp_line
			(start -0.7874 0.4064)
			(end -0.7874 -0.4064)
			(stroke
				(width 0.1524)
				(type default)
			)
			(layer "F.SilkS")
		)
		(fp_line
			(start 0.7874 0.4064)
			(end -0.7874 0.4064)
			(stroke
				(width 0.1524)
				(type default)
			)
			(layer "F.SilkS")
		)
		(fp_line
			(start -0.7874 -0.4064)
			(end 0.7874 -0.4064)
			(stroke
				(width 0.1524)
				(type default)
			)
			(layer "F.SilkS")
		)
		(fp_line
			(start 0.7874 -0.4064)
			(end 0.7874 0.4064)
			(stroke
				(width 0.1524)
				(type default)
			)
			(layer "F.SilkS")
		)
		(fp_line
			(start -0.67945 0.3048)
			(end -0.67945 -0.305054)
			(stroke
				(width 0.1)
				(type default)
			)
			(layer "F.Fab")
		)
		(fp_line
			(start -0.12065 0.3048)
			(end -0.67945 0.3048)
			(stroke
				(width 0.1)
				(type default)
			)
			(layer "F.Fab")
		)
		(fp_line
			(start 0.120396 0.3048)
			(end 0.120396 0.2794)
			(stroke
				(width 0.1)
				(type default)
			)
			(layer "F.Fab")
		)
		(fp_line
			(start 0.67945 0.3048)
			(end 0.120396 0.3048)
			(stroke
				(width 0.1)
				(type default)
			)
			(layer "F.Fab")
		)
		(fp_line
			(start -0.12065 0.2794)
			(end -0.12065 0.3048)
			(stroke
				(width 0.1)
				(type default)
			)
			(layer "F.Fab")
		)
		(fp_line
			(start 0.120396 0.2794)
			(end -0.12065 0.2794)
			(stroke
				(width 0.1)
				(type default)
			)
			(layer "F.Fab")
		)
		(fp_line
			(start -0.12065 -0.2794)
			(end 0.12065 -0.2794)
			(stroke
				(width 0.1)
				(type default)
			)
			(layer "F.Fab")
		)
		(fp_line
			(start 0.12065 -0.2794)
			(end 0.12065 -0.3048)
			(stroke
				(width 0.1)
				(type default)
			)
			(layer "F.Fab")
		)
		(fp_line
			(start 0.12065 -0.3048)
			(end 0.67945 -0.3048)
			(stroke
				(width 0.1)
				(type default)
			)
			(layer "F.Fab")
		)
		(fp_line
			(start 0.67945 -0.3048)
			(end 0.67945 0.3048)
			(stroke
				(width 0.1)
				(type default)
			)
			(layer "F.Fab")
		)
		(fp_line
			(start -0.67945 -0.305054)
			(end -0.12065 -0.305054)
			(stroke
				(width 0.1)
				(type default)
			)
			(layer "F.Fab")
		)
		(fp_line
			(start -0.12065 -0.305054)
			(end -0.12065 -0.2794)
			(stroke
				(width 0.1)
				(type default)
			)
			(layer "F.Fab")
		)
		(pad "1" smd circle
			(at -0.40005 0 270)
			(size 0 0)
			(layers "F.Cu" "F.Mask" "F.Paste")
			(net "SPI_BIC1_MISO_LS23_R")
		)
		(pad "2" smd circle
			(at 0.40005 0 270)
			(size 0 0)
			(layers "F.Cu" "F.Mask" "F.Paste")
			(net "SPI_BIC1_MISO_LS23")
		)
	)
)
